# T6G (Grand Teton) — schematic netlist excerpt (pin names and nets, part order shuffled) for the footprints in the layout excerpt that follows; sources: Cadence DE-HDL packaged netlist, KiCad conversion of 04192023_DAF0TMB3IC0_F0TG_MB_C_brd_V02_OCP.brd

R379  Q_RES  15 1% CHIP  pkg 0402LF  page 14 : A = M_E_CPU0_ALERT_N ; B = M_E_CPU0_ALERT_R_N
R4573  Q_RES  0 5% EMPTY  pkg 0402LF  page 125 : A = PRSNT_CABLE_GPU_B3_N ; B = PRSNT_CABLE_GPU_B3_ISO_N

(kicad_pcb
	(version 20260206)
	(generator "pcbnew")
	(generator_version "10.0")
	(general
		(thickness 1.6)
		(legacy_teardrops no)
	)
	(paper "A4")
	(title_block
		(title "04192023_DAF0TMB3IC0_F0TG_MB_C_brd_V02_OCP.brd")
		(comment 1 "Grand Teton / footprints 5206-5207 of 8354")
	)
	(layers
		(0 "F.Cu" signal "TOP")
		(4 "In1.Cu" signal "GND")
		(6 "In2.Cu" signal "IN1")
		(8 "In3.Cu" signal "GND1")
		(10 "In4.Cu" signal "IN2")
		(12 "In5.Cu" signal "GND2")
		(14 "In6.Cu" signal "IN3")
		(16 "In7.Cu" signal "GND3")
		(18 "In8.Cu" signal "VCC")
		(20 "In9.Cu" signal "VCC1")
		(22 "In10.Cu" signal "GND4")
		(24 "In11.Cu" signal "IN4")
		(26 "In12.Cu" signal "GND5")
		(28 "In13.Cu" signal "IN5")
		(30 "In14.Cu" signal "GND6")
		(32 "In15.Cu" signal "IN6")
		(34 "In16.Cu" signal "GND7")
		(2 "B.Cu" signal "BOTTOM")
		(9 "F.Adhes" user "F.Adhesive")
		(11 "B.Adhes" user "B.Adhesive")
		(13 "F.Paste" user "Package Geometry/Pastemask Top")
		(15 "B.Paste" user "Package Geometry/Pastemask Bottom")
		(5 "F.SilkS" user "Ref Des/Silkscreen Top")
		(7 "B.SilkS" user "Ref Des/Silkscreen Bottom")
		(1 "F.Mask" user "Board Geometry/Soldermask Top")
		(3 "B.Mask" user "Board Geometry/Soldermask Bottom")
		(17 "Dwgs.User" user "User.Drawings")
		(19 "Cmts.User" user "User.Comments")
		(21 "Eco1.User" user "User.Eco1")
		(23 "Eco2.User" user "User.Eco2")
		(25 "Edge.Cuts" user "Board Geometry/Outline")
		(27 "Margin" user)
		(31 "F.CrtYd" user "Package Geometry/Place Bound Top")
		(29 "B.CrtYd" user "Package Geometry/Place Bound Bottom")
		(35 "F.Fab" user "Ref Des/Assembly Top")
		(33 "B.Fab" user "Ref Des/Assembly Bottom")
	)
	(footprint ""
		(layer "B.Cu")
		(at 165.419532 -435.13248 -90)
		(property "Reference" "R4573"
			(at 0 0 90)
			(layer "B.SilkS")
			(hide yes)
			(effects
				(font
					(size 1.27 1.27)
				)
				(justify mirror)
			)
		)
		(property "Value" ""
			(at 0 0 90)
			(layer "B.Fab")
			(effects
				(font
					(size 1.27 1.27)
				)
				(justify mirror)
			)
		)
		(duplicate_pad_numbers_are_jumpers no)
		(fp_line
			(start -0.7874 0.4064)
			(end 0.7874 0.4064)
			(stroke
				(width 0.1524)
				(type default)
			)
			(layer "B.SilkS")
		)
		(fp_line
			(start 0.7874 0.4064)
			(end 0.7874 -0.4064)
			(stroke
				(width 0.1524)
				(type default)
			)
			(layer "B.SilkS")
		)
		(fp_line
			(start -0.7874 -0.4064)
			(end -0.7874 0.4064)
			(stroke
				(width 0.1524)
				(type default)
			)
			(layer "B.SilkS")
		)
		(fp_line
			(start 0.7874 -0.4064)
			(end -0.7874 -0.4064)
			(stroke
				(width 0.1524)
				(type default)
			)
			(layer "B.SilkS")
		)
		(fp_line
			(start -0.67945 0.3048)
			(end -0.120396 0.3048)
			(stroke
				(width 0.1)
				(type default)
			)
			(layer "B.Fab")
		)
		(fp_line
			(start -0.120396 0.3048)
			(end -0.120396 0.2794)
			(stroke
				(width 0.1)
				(type default)
			)
			(layer "B.Fab")
		)
		(fp_line
			(start 0.12065 0.3048)
			(end 0.67945 0.3048)
			(stroke
				(width 0.1)
				(type default)
			)
			(layer "B.Fab")
		)
		(fp_line
			(start 0.67945 0.3048)
			(end 0.67945 -0.305054)
			(stroke
				(width 0.1)
				(type default)
			)
			(layer "B.Fab")
		)
		(fp_line
			(start -0.120396 0.2794)
			(end 0.12065 0.2794)
			(stroke
				(width 0.1)
				(type default)
			)
			(layer "B.Fab")
		)
		(fp_line
			(start 0.12065 0.2794)
			(end 0.12065 0.3048)
			(stroke
				(width 0.1)
				(type default)
			)
			(layer "B.Fab")
		)
		(fp_line
			(start -0.12065 -0.2794)
			(end -0.12065 -0.3048)
			(stroke
				(width 0.1)
				(type default)
			)
			(layer "B.Fab")
		)
		(fp_line
			(start 0.12065 -0.2794)
			(end -0.12065 -0.2794)
			(stroke
				(width 0.1)
				(type default)
			)
			(layer "B.Fab")
		)
		(fp_line
			(start -0.67945 -0.3048)
			(end -0.67945 0.3048)
			(stroke
				(width 0.1)
				(type default)
			)
			(layer "B.Fab")
		)
		(fp_line
			(start -0.12065 -0.3048)
			(end -0.67945 -0.3048)
			(stroke
				(width 0.1)
				(type default)
			)
			(layer "B.Fab")
		)
		(fp_line
			(start 0.12065 -0.305054)
			(end 0.12065 -0.2794)
			(stroke
				(width 0.1)
				(type default)
			)
			(layer "B.Fab")
		)
		(fp_line
			(start 0.67945 -0.305054)
			(end 0.12065 -0.305054)
			(stroke
				(width 0.1)
				(type default)
			)
			(layer "B.Fab")
		)
		(pad "1" smd circle
			(at 0.40005 0 90)
			(size 0 0)
			(layers "B.Cu" "B.Mask" "B.Paste")
			(net "PRSNT_CABLE_GPU_B3_N")
		)
		(pad "2" smd circle
			(at -0.40005 0 90)
			(size 0 0)
			(layers "B.Cu" "B.Mask" "B.Paste")
			(net "PRSNT_CABLE_GPU_B3_ISO_N")
		)
	)
	(footprint ""
		(layer "B.Cu")
		(at 278.189182 -244.08511 180)
		(property "Reference" "R379"
			(at 0 0 0)
			(layer "B.SilkS")
			(hide yes)
			(effects
				(font
					(size 1.27 1.27)
				)
				(justify mirror)
			)
		)
		(property "Value" ""
			(at 0 0 0)
			(layer "B.Fab")
			(effects
				(font
					(size 1.27 1.27)
				)
				(justify mirror)
			)
		)
		(duplicate_pad_numbers_are_jumpers no)
		(fp_line
			(start 0.7874 0.4064)
			(end 0.7874 -0.4064)
			(stroke
				(width 0.1524)
				(type default)
			)
			(layer "B.SilkS")
		)
		(fp_line
			(start 0.7874 -0.4064)
			(end -0.7874 -0.4064)
			(stroke
				(width 0.1524)
				(type default)
			)
			(layer "B.SilkS")
		)
		(fp_line
			(start -0.7874 0.4064)
			(end 0.7874 0.4064)
			(stroke
				(width 0.1524)
				(type default)
			)
			(layer "B.SilkS")
		)
		(fp_line
			(start -0.7874 -0.4064)
			(end -0.7874 0.4064)
			(stroke
				(width 0.1524)
				(type default)
			)
			(layer "B.SilkS")
		)
		(fp_line
			(start 0.67945 0.3048)
			(end 0.67945 -0.305054)
			(stroke
				(width 0.1)
				(type default)
			)
			(layer "B.Fab")
		)
		(fp_line
			(start 0.67945 -0.305054)
			(end 0.12065 -0.305054)
			(stroke
				(width 0.1)
				(type default)
			)
			(layer "B.Fab")
		)
		(fp_line
			(start 0.12065 0.3048)
			(end 0.67945 0.3048)
			(stroke
				(width 0.1)
				(type default)
			)
			(layer "B.Fab")
		)
		(fp_line
			(start 0.12065 0.2794)
			(end 0.12065 0.3048)
			(stroke
				(width 0.1)
				(type default)
			)
			(layer "B.Fab")
		)
		(fp_line
			(start 0.12065 -0.2794)
			(end -0.12065 -0.2794)
			(stroke
				(width 0.1)
				(type default)
			)
			(layer "B.Fab")
		)
		(fp_line
			(start 0.12065 -0.305054)
			(end 0.12065 -0.2794)
			(stroke
				(width 0.1)
				(type default)
			)
			(layer "B.Fab")
		)
		(fp_line
			(start -0.120396 0.3048)
			(end -0.120396 0.2794)
			(stroke
				(width 0.1)
				(type default)
			)
			(layer "B.Fab")
		)
		(fp_line
			(start -0.120396 0.2794)
			(end 0.12065 0.2794)
			(stroke
				(width 0.1)
				(type default)
			)
			(layer "B.Fab")
		)
		(fp_line
			(start -0.12065 -0.2794)
			(end -0.12065 -0.3048)
			(stroke
				(width 0.1)
				(type default)
			)
			(layer "B.Fab")
		)
		(fp_line
			(start -0.12065 -0.3048)
			(end -0.67945 -0.3048)
			(stroke
				(width 0.1)
				(type default)
			)
			(layer "B.Fab")
		)
		(fp_line
			(start -0.67945 0.3048)
			(end -0.120396 0.3048)
			(stroke
				(width 0.1)
				(type default)
			)
			(layer "B.Fab")
		)
		(fp_line
			(start -0.67945 -0.3048)
			(end -0.67945 0.3048)
			(stroke
				(width 0.1)
				(type default)
			)
			(layer "B.Fab")
		)
		(pad "1" smd circle
			(at 0.40005 0)
			(size 0 0)
			(layers "B.Cu" "B.Mask" "B.Paste")
			(net "M_E_CPU0_ALERT_N")
		)
		(pad "2" smd circle
			(at -0.40005 0)
			(size 0 0)
			(layers "B.Cu" "B.Mask" "B.Paste")
			(net "M_E_CPU0_ALERT_R_N")
		)
	)
)
